(kicad_pcb
	(version 20260206)
	(generator "pcbnew")
	(generator_version "10.0")
	(general
		(thickness 1.6)
		(legacy_teardrops no)
	)
	(paper "A4")
	(title_block
		(title "pdpb — Lightning_PDPB_BRD.brd")
		(comment 1 "Lightning (Wiwynn / Facebook NVMe JBOF) / footprints 222-222 of 1140")
	)
	(layers
		(0 "F.Cu" signal "TOP")
		(4 "In1.Cu" signal "L2GND")
		(6 "In2.Cu" signal "L3")
		(8 "In3.Cu" signal "L4VCC")
		(10 "In4.Cu" signal "L5VCC")
		(12 "In5.Cu" signal "L6")
		(14 "In6.Cu" signal "L7GND")
		(2 "B.Cu" signal "BOTTOM")
		(9 "F.Adhes" user "F.Adhesive")
		(11 "B.Adhes" user "B.Adhesive")
		(13 "F.Paste" user "Package Geometry/Pastemask Top")
		(15 "B.Paste" user "Package Geometry/Pastemask Bottom")
		(5 "F.SilkS" user "Ref Des/Silkscreen Top")
		(7 "B.SilkS" user "Ref Des/Silkscreen Bottom")
		(1 "F.Mask" user "Board Geometry/Soldermask Top")
		(3 "B.Mask" user "Board Geometry/Soldermask Bottom")
		(17 "Dwgs.User" user "User.Drawings")
		(19 "Cmts.User" user "User.Comments")
		(21 "Eco1.User" user "User.Eco1")
		(23 "Eco2.User" user "User.Eco2")
		(25 "Edge.Cuts" user "Board Geometry/Outline")
		(27 "Margin" user)
		(31 "F.CrtYd" user "Package Geometry/Place Bound Top")
		(29 "B.CrtYd" user "Package Geometry/Place Bound Bottom")
		(35 "F.Fab" user "Ref Des/Assembly Top")
		(33 "B.Fab" user "Ref Des/Assembly Bottom")
	)
	(footprint ""
		(layer "F.Cu")
		(at 41.150032 -273.670014 90)
		(property "Reference" "J7"
			(at 0 0 90)
			(layer "F.SilkS")
			(hide yes)
			(effects
				(font
					(size 1.27 1.27)
				)
			)
		)
		(property "Value" "PCISLT68-14-GP-U1"
			(at -22.225 12.7508 90)
			(unlocked yes)
			(layer "F.Fab")
			(hide yes)
			(effects
				(font
					(size 1.016 1.016)
					(thickness 0.1524)
				)
			)
		)
		(property "Device Type" "SD-78827-0001"
			(at -22.225 11.2268 90)
			(unlocked yes)
			(layer "F.Fab")
			(hide yes)
			(effects
				(font
					(size 1.016 1.016)
					(thickness 0.1524)
				)
			)
		)
		(duplicate_pad_numbers_are_jumpers no)
		(fp_line
			(start 20.4724 -3.4036)
			(end 20.4724 0.0254)
			(stroke
				(width 0.1524)
				(type default)
			)
			(layer "F.SilkS")
		)
		(fp_line
			(start -20.4724 -3.4036)
			(end 20.4724 -3.4036)
			(stroke
				(width 0.1524)
				(type default)
			)
			(layer "F.SilkS")
		)
		(fp_line
			(start 23.749 0.0254)
			(end 23.749 4.6736)
			(stroke
				(width 0.1524)
				(type default)
			)
			(layer "F.SilkS")
		)
		(fp_line
			(start 20.4724 0.0254)
			(end 23.749 0.0254)
			(stroke
				(width 0.1524)
				(type default)
			)
			(layer "F.SilkS")
		)
		(fp_line
			(start -20.4724 0.0254)
			(end -20.4724 -3.4036)
			(stroke
				(width 0.1524)
				(type default)
			)
			(layer "F.SilkS")
		)
		(fp_line
			(start -23.749 0.0254)
			(end -20.4724 0.0254)
			(stroke
				(width 0.1524)
				(type default)
			)
			(layer "F.SilkS")
		)
		(fp_line
			(start 23.117556 1.803908)
			(end 23.117556 2.896108)
			(stroke
				(width 0.3048)
				(type default)
			)
			(layer "F.SilkS")
		)
		(fp_line
			(start -20.882356 1.803908)
			(end -20.882356 2.896108)
			(stroke
				(width 0.3048)
				(type default)
			)
			(layer "F.SilkS")
		)
		(fp_line
			(start 20.882356 2.896108)
			(end 20.882356 1.803908)
			(stroke
				(width 0.3048)
				(type default)
			)
			(layer "F.SilkS")
		)
		(fp_line
			(start -23.117556 2.896108)
			(end -23.117556 1.803908)
			(stroke
				(width 0.3048)
				(type default)
			)
			(layer "F.SilkS")
		)
		(fp_line
			(start 23.749 4.6736)
			(end 20.4724 4.6736)
			(stroke
				(width 0.1524)
				(type default)
			)
			(layer "F.SilkS")
		)
		(fp_line
			(start 20.4724 4.6736)
			(end 20.4724 12.0142)
			(stroke
				(width 0.1524)
				(type default)
			)
			(layer "F.SilkS")
		)
		(fp_line
			(start -20.4724 4.6736)
			(end -23.749 4.6736)
			(stroke
				(width 0.1524)
				(type default)
			)
			(layer "F.SilkS")
		)
		(fp_line
			(start -23.749 4.6736)
			(end -23.749 0.0254)
			(stroke
				(width 0.1524)
				(type default)
			)
			(layer "F.SilkS")
		)
		(fp_line
			(start 17.8435 10.3124)
			(end -17.8435 10.3124)
			(stroke
				(width 0.1524)
				(type default)
			)
			(layer "F.SilkS")
		)
		(fp_line
			(start -17.8435 10.3124)
			(end -17.8435 12.0142)
			(stroke
				(width 0.1524)
				(type default)
			)
			(layer "F.SilkS")
		)
		(fp_line
			(start 20.4724 12.0142)
			(end 17.8435 12.0142)
			(stroke
				(width 0.1524)
				(type default)
			)
			(layer "F.SilkS")
		)
		(fp_line
			(start 17.8435 12.0142)
			(end 17.8435 10.3124)
			(stroke
				(width 0.1524)
				(type default)
			)
			(layer "F.SilkS")
		)
		(fp_line
			(start -17.8435 12.0142)
			(end -20.4724 12.0142)
			(stroke
				(width 0.1524)
				(type default)
			)
			(layer "F.SilkS")
		)
		(fp_line
			(start -20.4724 12.0142)
			(end -20.4724 4.6736)
			(stroke
				(width 0.1524)
				(type default)
			)
			(layer "F.SilkS")
		)
		(fp_arc
			(start 20.882356 1.803908)
			(mid 21.999956 0.686308)
			(end 23.117556 1.803908)
			(stroke
				(width 0.3048)
				(type default)
			)
			(layer "F.SilkS")
		)
		(fp_arc
			(start -23.117556 1.803908)
			(mid -21.999956 0.686308)
			(end -20.882356 1.803908)
			(stroke
				(width 0.3048)
				(type default)
			)
			(layer "F.SilkS")
		)
		(fp_arc
			(start 23.117556 2.896108)
			(mid 21.999956 4.013708)
			(end 20.882356 2.896108)
			(stroke
				(width 0.3048)
				(type default)
			)
			(layer "F.SilkS")
		)
		(fp_arc
			(start -20.882356 2.896108)
			(mid -21.999956 4.013708)
			(end -23.117556 2.896108)
			(stroke
				(width 0.3048)
				(type default)
			)
			(layer "F.SilkS")
		)
		(fp_poly
			(pts
				(xy -20.2184 11.7602) (xy -20.2184 4.4196) (xy -23.495 4.4196) (xy -23.495 0.2794) (xy -20.2184 0.2794)
				(xy -20.2184 -3.1496) (xy 20.2184 -3.1496) (xy 20.2184 0.2794) (xy 23.495 0.2794) (xy 23.495 4.4196)
				(xy 20.2184 4.4196) (xy 20.2184 11.7602) (xy 18.0975 11.7602) (xy 18.0975 10.0584) (xy -18.0975 10.0584)
				(xy -18.0975 11.7602)
			)
			(stroke
				(width 0)
				(type default)
			)
			(fill no)
			(layer "F.CrtYd")
		)
		(fp_poly
			(pts
				(xy -21.2471 16.256) (xy -21.2471 4.9276) (xy -24.003 4.9276) (xy -24.003 -0.2286) (xy -20.7264 -0.2286)
				(xy -20.7264 -3.6576) (xy 20.7264 -3.6576) (xy 20.7264 -0.2286) (xy 24.003 -0.2286) (xy 24.003 -0.00635)
				(xy 20.2184 -0.00635) (xy 20.2184 -3.1496) (xy -20.2184 -3.1496) (xy -20.2184 0.2794) (xy -23.495 0.2794)
				(xy -23.495 4.4196) (xy -20.2184 4.4196) (xy -20.2184 11.7602) (xy -18.0975 11.7602) (xy -18.0975 10.0584)
				(xy 18.0975 10.0584) (xy 18.0975 11.7602) (xy 20.2184 11.7602) (xy 20.2184 4.4196) (xy 23.495 4.4196)
				(xy 23.495 0.2794) (xy 20.2184 0.2794) (xy 20.2184 0.00635) (xy 24.003 0.00635) (xy 24.003 4.9276)
				(xy 21.2471 4.9276) (xy 21.2471 16.256)
			)
			(stroke
				(width 0)
				(type default)
			)
			(fill no)
			(layer "F.CrtYd")
		)
		(fp_poly
			(pts
				(xy -21.2471 16.256) (xy -21.2471 4.9276) (xy -24.003 4.9276) (xy -24.003 -0.2286) (xy -20.7264 -0.2286)
				(xy -20.7264 -3.6576) (xy 20.7264 -3.6576) (xy 20.7264 -0.2286) (xy 24.003 -0.2286) (xy 24.003 4.9276)
				(xy 21.2471 4.9276) (xy 21.2471 16.256)
			)
			(stroke
				(width 0)
				(type default)
			)
			(fill no)
			(layer "F.Fab")
		)
		(pad "" np_thru_hole circle
			(at -18.999962 0 90)
			(size 0.254 0.254)
			(drill 1.8542)
			(layers "*.Cu" "*.Mask")
			(clearance 1.1557)
			(thermal_gap 1.1557)
		)
		(pad "" np_thru_hole circle
			(at 18.999962 0 90)
			(size 0.254 0.254)
			(drill 1.8542)
			(layers "*.Cu" "*.Mask")
			(clearance 1.1557)
			(thermal_gap 1.1557)
		)
		(pad "E1" smd rect
			(at -7.079996 1.240028 90)
			(size 0.508 2.0066)
			(layers "F.Cu" "F.Mask" "F.Paste")
			(net "PE_CLK100M_DR7_2_P")
		)
		(pad "E2" smd rect
			(at -6.279896 1.240028 90)
			(size 0.508 2.0066)
			(layers "F.Cu" "F.Mask" "F.Paste")
			(net "PE_CLK100M_DR7_2_N")
		)
		(pad "E3" smd rect
			(at -5.48005 1.240028 90)
			(size 0.508 2.0066)
			(layers "F.Cu" "F.Mask" "F.Paste")
			(net "P3V3")
		)
		(pad "E4" smd rect
			(at -4.67995 1.240028 90)
			(size 0.508 2.0066)
			(layers "F.Cu" "F.Mask" "F.Paste")
			(net "SSD7_PERST_N")
		)
		(pad "E5" smd rect
			(at -3.880104 1.240028 90)
			(size 0.508 2.0066)
			(layers "F.Cu" "F.Mask" "F.Paste")
			(net "SSD7_PERST_N")
		)
		(pad "E6" smd rect
			(at -3.080004 1.240028 90)
			(size 0.508 2.0066)
			(layers "F.Cu" "F.Mask" "F.Paste")
			(net "Net_1107")
		)
		(pad "E7" smd rect
			(at -15.48003 -1.949958 90)
			(size 0.508 2.0066)
			(layers "F.Cu" "F.Mask" "F.Paste")
			(net "PE_CLK100M_DR7_1_P")
		)
		(pad "E8" smd rect
			(at -14.67993 -1.949958 90)
			(size 0.508 2.0066)
			(layers "F.Cu" "F.Mask" "F.Paste")
			(net "PE_CLK100M_DR7_1_N")
		)
		(pad "E9" smd rect
			(at -13.880084 -1.949958 90)
			(size 0.508 2.0066)
			(layers "F.Cu" "F.Mask" "F.Paste")
			(net "GND")
		)
		(pad "E10" smd rect
			(at -13.079984 -1.949958 90)
			(size 0.508 2.0066)
			(layers "F.Cu" "F.Mask" "F.Paste")
			(net "PE_TX1_DR7_N")
		)
		(pad "E11" smd rect
			(at -12.279884 -1.949958 90)
			(size 0.508 2.0066)
			(layers "F.Cu" "F.Mask" "F.Paste")
			(net "PE_TX1_DR7_P")
		)
		(pad "E12" smd rect
			(at -11.480038 -1.949958 90)
			(size 0.508 2.0066)
			(layers "F.Cu" "F.Mask" "F.Paste")
			(net "GND")
		)
		(pad "E13" smd rect
			(at -10.679938 -1.949958 90)
			(size 0.508 2.0066)
			(layers "F.Cu" "F.Mask" "F.Paste")
			(net "PE_RX1_DR7_N")
		)
		(pad "E14" smd rect
			(at -9.880092 -1.949958 90)
			(size 0.508 2.0066)
			(layers "F.Cu" "F.Mask" "F.Paste")
			(net "PE_RX1_DR7_P")
		)
		(pad "E15" smd rect
			(at -9.079992 -1.949958 90)
			(size 0.508 2.0066)
			(layers "F.Cu" "F.Mask" "F.Paste")
			(net "GND")
		)
		(pad "E16" smd rect
			(at -8.279892 -1.949958 90)
			(size 0.508 2.0066)
			(layers "F.Cu" "F.Mask" "F.Paste")
			(net "Net_1114")
		)
		(pad "E17" smd rect
			(at 9.320022 -1.949958 90)
			(size 0.508 2.0066)
			(layers "F.Cu" "F.Mask" "F.Paste")
			(net "PE_TX4_DR7_N")
		)
		(pad "E18" smd rect
			(at 10.120122 -1.949958 90)
			(size 0.508 2.0066)
			(layers "F.Cu" "F.Mask" "F.Paste")
			(net "PE_TX4_DR7_P")
		)
		(pad "E19" smd rect
			(at 10.919968 -1.949958 90)
			(size 0.508 2.0066)
			(layers "F.Cu" "F.Mask" "F.Paste")
			(net "GND")
		)
		(pad "E20" smd rect
			(at 11.720068 -1.949958 90)
			(size 0.508 2.0066)
			(layers "F.Cu" "F.Mask" "F.Paste")
			(net "PE_RX4_DR7_N")
		)
		(pad "E21" smd rect
			(at 12.519914 -1.949958 90)
			(size 0.508 2.0066)
			(layers "F.Cu" "F.Mask" "F.Paste")
			(net "PE_RX4_DR7_P")
		)
		(pad "E22" smd rect
			(at 13.320014 -1.949958 90)
			(size 0.508 2.0066)
			(layers "F.Cu" "F.Mask" "F.Paste")
			(net "GND")
		)
		(pad "E23" smd rect
			(at 14.120114 -1.949958 90)
			(size 0.508 2.0066)
			(layers "F.Cu" "F.Mask" "F.Paste")
			(net "SCL_DR7_R")
		)
		(pad "E24" smd rect
			(at 14.91996 -1.949958 90)
			(size 0.508 2.0066)
			(layers "F.Cu" "F.Mask" "F.Paste")
			(net "SDA_DR7_R")
		)
		(pad "E25" smd rect
			(at 15.72006 -1.949958 90)
			(size 0.508 2.0066)
			(layers "F.Cu" "F.Mask" "F.Paste")
			(net "DUALPORTEN#7")
		)
		(pad "P1" smd rect
			(at -1.905 0.824992 90)
			(size 0.6604 2.0574)
			(layers "F.Cu" "F.Mask" "F.Paste")
			(net "Net_1110")
		)
		(pad "P2" smd rect
			(at -0.635 0.824992 90)
			(size 0.6604 2.0574)
			(layers "F.Cu" "F.Mask" "F.Paste")
			(net "Net_1109")
		)
		(pad "P3" smd rect
			(at 0.635 0.824992 90)
			(size 0.6604 2.0574)
			(layers "F.Cu" "F.Mask" "F.Paste")
			(net "Net_1108")
		)
		(pad "P4" smd rect
			(at 1.905 0.824992 90)
			(size 0.6604 2.0574)
			(layers "F.Cu" "F.Mask" "F.Paste")
			(net "SSD7_CLK0_OE_N")
		)
		(pad "P5" smd rect
			(at 3.175 0.824992 90)
			(size 0.6604 2.0574)
			(layers "F.Cu" "F.Mask" "F.Paste")
			(net "GND")
		)
		(pad "P6" smd rect
			(at 4.445 0.824992 90)
			(size 0.6604 2.0574)
			(layers "F.Cu" "F.Mask" "F.Paste")
			(net "GND")
		)
		(pad "P7" smd rect
			(at 5.715 0.824992 90)
			(size 0.6604 2.0574)
			(layers "F.Cu" "F.Mask" "F.Paste")
			(net "Net_101")
		)
		(pad "P8" smd rect
			(at 6.985 0.824992 90)
			(size 0.6604 2.0574)
			(layers "F.Cu" "F.Mask" "F.Paste")
			(net "Net_71")
		)
		(pad "P9" smd rect
			(at 8.255 0.824992 90)
			(size 0.6604 2.0574)
			(layers "F.Cu" "F.Mask" "F.Paste")
			(net "Net_85")
		)
		(pad "P10" smd rect
			(at 9.525 0.824992 90)
			(size 0.6604 2.0574)
			(layers "F.Cu" "F.Mask" "F.Paste")
			(net "SSD_PRSNT_NET7")
		)
		(pad "P11" smd rect
			(at 10.795 0.824992 90)
			(size 0.6604 2.0574)
			(layers "F.Cu" "F.Mask" "F.Paste")
			(net "SSD_ACT_DR7")
		)
		(pad "P12" smd rect
			(at 12.065 0.824992 90)
			(size 0.6604 2.0574)
			(layers "F.Cu" "F.Mask" "F.Paste")
			(net "GND")
		)
		(pad "P13" smd rect
			(at 13.335 0.824992 90)
			(size 0.6604 2.0574)
			(layers "F.Cu" "F.Mask" "F.Paste")
			(net "12V_PRECH_SSD7")
		)
		(pad "P14" smd rect
			(at 14.605 0.824992 90)
			(size 0.6604 2.0574)
			(layers "F.Cu" "F.Mask" "F.Paste")
			(net "P12V_SSD7")
		)
		(pad "P15" smd rect
			(at 15.875 0.824992 90)
			(size 0.6604 2.0574)
			(layers "F.Cu" "F.Mask" "F.Paste")
			(net "P12V_SSD7")
		)
		(pad "PTH1" thru_hole oval
			(at -21.999956 2.350008 90)
			(size 1.524 2.6162)
			(drill oval 0.8128 1.905)
			(layers "*.Cu" "*.Mask")
			(remove_unused_layers no)
			(net "Net_1119")
			(clearance 0.1524)
			(thermal_gap 0.1524)
		)
		(pad "PTH2" thru_hole oval
			(at 21.999956 2.350008 90)
			(size 1.524 2.6162)
			(drill oval 0.8128 1.905)
			(layers "*.Cu" "*.Mask")
			(remove_unused_layers no)
			(net "Net_1103")
			(clearance 0.1524)
			(thermal_gap 0.1524)
		)
		(pad "S1" smd rect
			(at -15.875 0.824992 90)
			(size 0.6604 2.0574)
			(layers "F.Cu" "F.Mask" "F.Paste")
			(net "GND")
		)
		(pad "S2" smd rect
			(at -14.605 0.824992 90)
			(size 0.6604 2.0574)
			(layers "F.Cu" "F.Mask" "F.Paste")
			(net "Net_1118")
		)
		(pad "S3" smd rect
			(at -13.335 0.824992 90)
			(size 0.6604 2.0574)
			(layers "F.Cu" "F.Mask" "F.Paste")
			(net "Net_1117")
		)
		(pad "S4" smd rect
			(at -12.065 0.824992 90)
			(size 0.6604 2.0574)
			(layers "F.Cu" "F.Mask" "F.Paste")
			(net "GND")
		)
		(pad "S5" smd rect
			(at -10.795 0.824992 90)
			(size 0.6604 2.0574)
			(layers "F.Cu" "F.Mask" "F.Paste")
			(net "Net_1116")
		)
		(pad "S6" smd rect
			(at -9.525 0.824992 90)
			(size 0.6604 2.0574)
			(layers "F.Cu" "F.Mask" "F.Paste")
			(net "Net_1115")
		)
		(pad "S7" smd rect
			(at -8.255 0.824992 90)
			(size 0.6604 2.0574)
			(layers "F.Cu" "F.Mask" "F.Paste")
			(net "GND")
		)
		(pad "S8" smd rect
			(at -7.480046 -1.949958 90)
			(size 0.508 2.0066)
			(layers "F.Cu" "F.Mask" "F.Paste")
			(net "GND")
		)
		(pad "S9" smd rect
			(at -6.679946 -1.949958 90)
			(size 0.508 2.0066)
			(layers "F.Cu" "F.Mask" "F.Paste")
			(net "Net_1113")
		)
		(pad "S10" smd rect
			(at -5.8801 -1.949958 90)
			(size 0.508 2.0066)
			(layers "F.Cu" "F.Mask" "F.Paste")
			(net "Net_1112")
		)
		(pad "S11" smd rect
			(at -5.08 -1.949958 90)
			(size 0.508 2.0066)
			(layers "F.Cu" "F.Mask" "F.Paste")
			(net "GND")
		)
		(pad "S12" smd rect
			(at -4.2799 -1.949958 90)
			(size 0.508 2.0066)
			(layers "F.Cu" "F.Mask" "F.Paste")
			(net "Net_1111")
		)
		(pad "S13" smd rect
			(at -3.480054 -1.949958 90)
			(size 0.508 2.0066)
			(layers "F.Cu" "F.Mask" "F.Paste")
			(net "Net_1106")
		)
		(pad "S14" smd rect
			(at -2.679954 -1.949958 90)
			(size 0.508 2.0066)
			(layers "F.Cu" "F.Mask" "F.Paste")
			(net "GND")
		)
		(pad "S15" smd rect
			(at -1.880108 -1.949958 90)
			(size 0.508 2.0066)
			(layers "F.Cu" "F.Mask" "F.Paste")
			(net "Net_1105")
		)
		(pad "S16" smd rect
			(at -1.080008 -1.949958 90)
			(size 0.508 2.0066)
			(layers "F.Cu" "F.Mask" "F.Paste")
			(net "GND")
		)
		(pad "S17" smd rect
			(at -0.279908 -1.949958 90)
			(size 0.508 2.0066)
			(layers "F.Cu" "F.Mask" "F.Paste")
			(net "PE_TX2_DR7_N")
		)
		(pad "S18" smd rect
			(at 0.519938 -1.949958 90)
			(size 0.508 2.0066)
			(layers "F.Cu" "F.Mask" "F.Paste")
			(net "PE_TX2_DR7_P")
		)
		(pad "S19" smd rect
			(at 1.320038 -1.949958 90)
			(size 0.508 2.0066)
			(layers "F.Cu" "F.Mask" "F.Paste")
			(net "GND")
		)
		(pad "S20" smd rect
			(at 2.119884 -1.949958 90)
			(size 0.508 2.0066)
			(layers "F.Cu" "F.Mask" "F.Paste")
			(net "PE_RX2_DR7_N")
		)
		(pad "S21" smd rect
			(at 2.919984 -1.949958 90)
			(size 0.508 2.0066)
			(layers "F.Cu" "F.Mask" "F.Paste")
			(net "PE_RX2_DR7_P")
		)
		(pad "S22" smd rect
			(at 3.720084 -1.949958 90)
			(size 0.508 2.0066)
			(layers "F.Cu" "F.Mask" "F.Paste")
			(net "GND")
		)
		(pad "S23" smd rect
			(at 4.51993 -1.949958 90)
			(size 0.508 2.0066)
			(layers "F.Cu" "F.Mask" "F.Paste")
			(net "PE_TX3_DR7_N")
		)
		(pad "S24" smd rect
			(at 5.32003 -1.949958 90)
			(size 0.508 2.0066)
			(layers "F.Cu" "F.Mask" "F.Paste")
			(net "PE_TX3_DR7_P")
		)
		(pad "S25" smd rect
			(at 6.119876 -1.949958 90)
			(size 0.508 2.0066)
			(layers "F.Cu" "F.Mask" "F.Paste")
			(net "GND")
		)
		(pad "S26" smd rect
			(at 6.919976 -1.949958 90)
			(size 0.508 2.0066)
			(layers "F.Cu" "F.Mask" "F.Paste")
			(net "PE_RX3_DR7_N")
		)
		(pad "S27" smd rect
			(at 7.720076 -1.949958 90)
			(size 0.508 2.0066)
			(layers "F.Cu" "F.Mask" "F.Paste")
			(net "PE_RX3_DR7_P")
		)
		(pad "S28" smd rect
			(at 8.519922 -1.949958 90)
			(size 0.508 2.0066)
			(layers "F.Cu" "F.Mask" "F.Paste")
			(net "GND")
		)
		(zone
			(layers "F.Cu" "B.Cu" "In1.Cu" "In2.Cu" "In3.Cu" "In4.Cu" "In5.Cu" "In6.Cu")
			(hatch none 0.5)
			(connect_pads
				(clearance 0)
			)
			(min_thickness 0.25)
			(keepout
				(tracks not_allowed)
				(vias allowed)
				(pads allowed)
				(copperpour not_allowed)
				(footprints allowed)
			)
			(placement
				(enabled no)
				(sheetname "")
			)
			(fill
				(thermal_gap 0.5)
				(thermal_bridge_width 0.5)
				(island_removal_mode 0)
			)
			(polygon
				(pts
					(arc
						(start 42.381932 -292.669976)
						(mid 39.918132 -292.669976)
						(end 42.381932 -292.669976)
					)
				)
			)
		)
		(zone
			(layers "F.Cu" "B.Cu" "In1.Cu" "In2.Cu" "In3.Cu" "In4.Cu" "In5.Cu" "In6.Cu")
			(hatch none 0.5)
			(connect_pads
				(clearance 0)
			)
			(min_thickness 0.25)
			(keepout
				(tracks not_allowed)
				(vias allowed)
				(pads allowed)
				(copperpour not_allowed)
				(footprints allowed)
			)
			(placement
				(enabled no)
				(sheetname "")
			)
			(fill
				(thermal_gap 0.5)
				(thermal_bridge_width 0.5)
				(island_removal_mode 0)
			)
			(polygon
				(pts
					(arc
						(start 42.381932 -254.670052)
						(mid 39.918132 -254.670052)
						(end 42.381932 -254.670052)
					)
				)
			)
		)
	)
)
